# BASEBOARD_FAB2 (Tioga Pass) — schematic netlist excerpt (pin names and nets, part order shuffled) for the footprints in the layout excerpt that follows; sources: Cadence DE-HDL packaged netlist, KiCad conversion of Wiwynn_Tioga_Pass_MB.brd

R8G11  RES  0.0 5% EMPTY  pkg 0402  page 189 : A = JTAG_PCH_PLD_TMS ; B = JTAG_TMS

R1D49  RES_PWR  0.001 1% CHIP  pkg 6PAD  page 200
  \1\  = P12V_PSU
  \2\  = P12V_MB0_SW
  \3\  = P12V_HSC_SENP0
  \4\  = P12V_HSC_SENN0
  \5\  = P12V_PSU
  \6\  = P12V_MB0_SW

C5G18  CAP_A  47UF 4V 20% X5R  pkg 0603V  page 217 : A = PVDDQ_ABC ; B = GND

(kicad_pcb
	(version 20260206)
	(generator "pcbnew")
	(generator_version "10.0")
	(general
		(thickness 1.6)
		(legacy_teardrops no)
	)
	(paper "A4")
	(title_block
		(title "Wiwynn_Tioga_Pass_MB.brd")
		(comment 1 "Tioga Pass / footprints 1097-1099 of 4770")
	)
	(layers
		(0 "F.Cu" signal "TOP")
		(4 "In1.Cu" signal "L2GND")
		(6 "In2.Cu" signal "L3")
		(8 "In3.Cu" signal "L4GND")
		(10 "In4.Cu" signal "L5")
		(12 "In5.Cu" signal "L6GND")
		(14 "In6.Cu" signal "L7VCC")
		(16 "In7.Cu" signal "L8VCC")
		(18 "In8.Cu" signal "L9GND")
		(20 "In9.Cu" signal "L10")
		(22 "In10.Cu" signal "L11GND")
		(24 "In11.Cu" signal "L12")
		(26 "In12.Cu" signal "L13GND")
		(2 "B.Cu" signal "BOTTOM")
		(9 "F.Adhes" user "F.Adhesive")
		(11 "B.Adhes" user "B.Adhesive")
		(13 "F.Paste" user "Package Geometry/Pastemask Top")
		(15 "B.Paste" user "Package Geometry/Pastemask Bottom")
		(5 "F.SilkS" user "Ref Des/Silkscreen Top")
		(7 "B.SilkS" user "Ref Des/Silkscreen Bottom")
		(1 "F.Mask" user "Board Geometry/Soldermask Top")
		(3 "B.Mask" user "Board Geometry/Soldermask Bottom")
		(17 "Dwgs.User" user "User.Drawings")
		(19 "Cmts.User" user "User.Comments")
		(21 "Eco1.User" user "User.Eco1")
		(23 "Eco2.User" user "User.Eco2")
		(25 "Edge.Cuts" user "Board Geometry/Outline")
		(27 "Margin" user)
		(31 "F.CrtYd" user "Package Geometry/Place Bound Top")
		(29 "B.CrtYd" user "Package Geometry/Place Bound Bottom")
		(35 "F.Fab" user "Ref Des/Assembly Top")
		(33 "B.Fab" user "Ref Des/Assembly Bottom")
	)
	(footprint ""
		(layer "F.Cu")
		(at 7.366 -66.3702)
		(property "Reference" "R1D49"
			(at -3.556 -2.56413 0)
			(unlocked yes)
			(layer "F.SilkS")
			(effects
				(font
					(size 0.7874 0.5842)
					(thickness 0.1524)
				)
				(justify left)
			)
		)
		(property "Value" ""
			(at 0 0 0)
			(layer "F.Fab")
			(effects
				(font
					(size 1.27 1.27)
				)
			)
		)
		(duplicate_pad_numbers_are_jumpers no)
		(fp_circle
			(center -2.07264 -0.597154)
			(end -1.94564 -0.597154)
			(stroke
				(width 0.254)
				(type default)
			)
			(fill no)
			(layer "F.SilkS")
		)
		(fp_rect
			(start -0.8001 -0.31242)
			(end 5.8039 3.11658)
			(stroke
				(width 0)
				(type default)
			)
			(fill no)
			(layer "F.CrtYd")
		)
		(fp_line
			(start -0.8001 -0.31242)
			(end 5.8039 -0.31242)
			(stroke
				(width 0.1)
				(type default)
			)
			(layer "F.Fab")
		)
		(fp_line
			(start -0.8001 3.11658)
			(end -0.8001 -0.31242)
			(stroke
				(width 0.1)
				(type default)
			)
			(layer "F.Fab")
		)
		(fp_line
			(start 5.8039 -0.31242)
			(end 5.8039 3.11658)
			(stroke
				(width 0.1)
				(type default)
			)
			(layer "F.Fab")
		)
		(fp_line
			(start 5.8039 3.11658)
			(end -0.8001 3.11658)
			(stroke
				(width 0.1)
				(type default)
			)
			(layer "F.Fab")
		)
		(fp_circle
			(center -1.740916 -1.623822)
			(end -1.613916 -1.623822)
			(stroke
				(width 0.254)
				(type default)
			)
			(fill no)
			(layer "F.Fab")
		)
		(pad "1" smd rect
			(at 0 0)
			(size 3.4036 1.1938)
			(layers "F.Cu" "F.Mask" "F.Paste")
			(net "P12V_PSU")
		)
		(pad "2" smd rect
			(at 5.0038 0)
			(size 3.4036 1.1938)
			(layers "F.Cu" "F.Mask" "F.Paste")
			(net "P12V_MB0_SW")
		)
		(pad "3" smd rect
			(at 0 1.40208)
			(size 3.4036 0.6096)
			(layers "F.Cu" "F.Mask" "F.Paste")
			(net "P12V_HSC_SENP0")
		)
		(pad "4" smd rect
			(at 5.0038 1.40208)
			(size 3.4036 0.6096)
			(layers "F.Cu" "F.Mask" "F.Paste")
			(net "P12V_HSC_SENN0")
		)
		(pad "5" smd rect
			(at 0 2.80416)
			(size 3.4036 1.1938)
			(layers "F.Cu" "F.Mask" "F.Paste")
			(net "P12V_PSU")
		)
		(pad "6" smd rect
			(at 5.0038 2.80416)
			(size 3.4036 1.1938)
			(layers "F.Cu" "F.Mask" "F.Paste")
			(net "P12V_MB0_SW")
		)
		(zone
			(layer "F.Cu")
			(hatch none 0.5)
			(connect_pads
				(clearance 0)
			)
			(min_thickness 0.25)
			(keepout
				(tracks allowed)
				(vias not_allowed)
				(pads allowed)
				(copperpour not_allowed)
				(footprints allowed)
			)
			(placement
				(enabled no)
				(sheetname "")
			)
			(fill
				(thermal_gap 0.5)
				(thermal_bridge_width 0.5)
				(island_removal_mode 0)
			)
			(polygon
				(pts
					(xy 9.0678 -66.75628) (xy 9.0678 -62.96914) (xy 10.668 -62.96914) (xy 10.668 -66.9671) (xy 9.11352 -66.9671)
					(xy 9.0678 -66.9671)
				)
			)
		)
	)
	(footprint ""
		(layer "F.Cu")
		(at 276.000464 -3.3528 90)
		(property "Reference" "C5G18"
			(at 1.848866 0.752348 90)
			(unlocked yes)
			(layer "F.SilkS")
			(effects
				(font
					(size 1.27 0.9652)
					(thickness 0.1524)
				)
			)
		)
		(property "Value" ""
			(at 0 0 90)
			(layer "F.Fab")
			(effects
				(font
					(size 1.27 1.27)
				)
			)
		)
		(duplicate_pad_numbers_are_jumpers no)
		(fp_rect
			(start -0.500126 1.598422)
			(end 0.500126 -0.201422)
			(stroke
				(width 0)
				(type default)
			)
			(fill no)
			(layer "F.CrtYd")
		)
		(fp_line
			(start 0.500126 -0.201422)
			(end 0.500126 1.598422)
			(stroke
				(width 0.1)
				(type default)
			)
			(layer "F.Fab")
		)
		(fp_line
			(start -0.500126 -0.201422)
			(end 0.500126 -0.201422)
			(stroke
				(width 0.1)
				(type default)
			)
			(layer "F.Fab")
		)
		(fp_line
			(start 0.500126 1.598422)
			(end -0.500126 1.598422)
			(stroke
				(width 0.1)
				(type default)
			)
			(layer "F.Fab")
		)
		(fp_line
			(start -0.500126 1.598422)
			(end -0.500126 -0.201422)
			(stroke
				(width 0.1)
				(type default)
			)
			(layer "F.Fab")
		)
		(pad "1" smd rect
			(at 0 0)
			(size 0.889 0.9906)
			(layers "F.Cu" "F.Mask" "F.Paste")
			(net "PVDDQ_ABC")
		)
		(pad "2" smd rect
			(at 0 1.397)
			(size 0.889 0.9906)
			(layers "F.Cu" "F.Mask" "F.Paste")
			(net "GND")
		)
		(zone
			(layer "F.Cu")
			(hatch none 0.5)
			(connect_pads
				(clearance 0)
			)
			(min_thickness 0.25)
			(keepout
				(tracks allowed)
				(vias not_allowed)
				(pads allowed)
				(copperpour not_allowed)
				(footprints allowed)
			)
			(placement
				(enabled no)
				(sheetname "")
			)
			(fill
				(thermal_gap 0.5)
				(thermal_bridge_width 0.5)
				(island_removal_mode 0)
			)
			(polygon
				(pts
					(xy 276.952964 -2.8575) (xy 276.952964 -3.8481) (xy 276.444964 -3.8481) (xy 276.444964 -2.8575)
				)
			)
		)
		(zone
			(layer "F.Cu")
			(hatch none 0.5)
			(connect_pads
				(clearance 0)
			)
			(min_thickness 0.25)
			(keepout
				(tracks not_allowed)
				(vias allowed)
				(pads allowed)
				(copperpour not_allowed)
				(footprints allowed)
			)
			(placement
				(enabled no)
				(sheetname "")
			)
			(fill
				(thermal_gap 0.5)
				(thermal_bridge_width 0.5)
				(island_removal_mode 0)
			)
			(polygon
				(pts
					(xy 276.952964 -2.8575) (xy 276.952964 -3.8481) (xy 276.444964 -3.8481) (xy 276.444964 -2.8575)
				)
			)
		)
	)
	(footprint ""
		(layer "F.Cu")
		(at 393.2936 -0.2286)
		(property "Reference" "R8G11"
			(at 0 0 0)
			(layer "F.SilkS")
			(hide yes)
			(effects
				(font
					(size 1.27 1.27)
				)
			)
		)
		(property "Value" ""
			(at 0 0 0)
			(layer "F.Fab")
			(effects
				(font
					(size 1.27 1.27)
				)
			)
		)
		(duplicate_pad_numbers_are_jumpers no)
		(fp_poly
			(pts
				(xy -0.2794 -0.1016) (xy 0.2794 -0.1016) (xy 0.2794 0.9906) (xy -0.2794 0.9906)
			)
			(stroke
				(width 0)
				(type default)
			)
			(fill no)
			(layer "F.CrtYd")
		)
		(fp_line
			(start -0.2794 -0.1016)
			(end -0.2794 0.9906)
			(stroke
				(width 0.1)
				(type default)
			)
			(layer "F.Fab")
		)
		(fp_line
			(start -0.2794 0.9906)
			(end 0.2794 0.9906)
			(stroke
				(width 0.1)
				(type default)
			)
			(layer "F.Fab")
		)
		(fp_line
			(start 0.2794 -0.1016)
			(end -0.2794 -0.1016)
			(stroke
				(width 0.1)
				(type default)
			)
			(layer "F.Fab")
		)
		(fp_line
			(start 0.2794 0.9906)
			(end 0.2794 -0.1016)
			(stroke
				(width 0.1)
				(type default)
			)
			(layer "F.Fab")
		)
		(pad "1" smd rect
			(at 0 0)
			(size 0.508 0.508)
			(layers "F.Cu" "F.Mask" "F.Paste")
			(net "JTAG_PCH_PLD_TMS")
		)
		(pad "2" smd rect
			(at 0 0.889)
			(size 0.508 0.508)
			(layers "F.Cu" "F.Mask" "F.Paste")
			(net "JTAG_TMS")
		)
		(zone
			(layer "F.Cu")
			(hatch none 0.5)
			(connect_pads
				(clearance 0)
			)
			(min_thickness 0.25)
			(keepout
				(tracks allowed)
				(vias not_allowed)
				(pads allowed)
				(copperpour not_allowed)
				(footprints allowed)
			)
			(placement
				(enabled no)
				(sheetname "")
			)
			(fill
				(thermal_gap 0.5)
				(thermal_bridge_width 0.5)
				(island_removal_mode 0)
			)
			(polygon
				(pts
					(xy 393.0396 0.0254) (xy 393.5476 0.0254) (xy 393.5476 0.4064) (xy 393.0396 0.4064)
				)
			)
		)
		(zone
			(layer "F.Cu")
			(hatch none 0.5)
			(connect_pads
				(clearance 0)
			)
			(min_thickness 0.25)
			(keepout
				(tracks not_allowed)
				(vias allowed)
				(pads allowed)
				(copperpour not_allowed)
				(footprints allowed)
			)
			(placement
				(enabled no)
				(sheetname "")
			)
			(fill
				(thermal_gap 0.5)
				(thermal_bridge_width 0.5)
				(island_removal_mode 0)
			)
			(polygon
				(pts
					(xy 393.0396 0.4064) (xy 393.5476 0.4064) (xy 393.5476 0.0254) (xy 393.0396 0.0254)
				)
			)
		)
	)
)
